# T6G (Grand Teton) — schematic netlist excerpt (pin names and nets, part order shuffled) for the footprints in the layout excerpt that follows; sources: Cadence DE-HDL packaged netlist, KiCad conversion of 04192023_DAF0TMB3IC0_F0TG_MB_C_brd_V02_OCP.brd

R629  Q_RES  51.1 1% EMPTY  pkg 0201LF  page 287 : A = CLK_100M_RETIMER_CPU0_P1_DN ; B = GND
R1567  Q_RES  4.7K 5% CHIP  pkg 0402LF  page 77 : A = PVDD18_S5_P0 ; B = ROM_LS_EN
R1300  Q_RES  0 5% CHIP  pkg 0402LF  page 159 : A = I3C_SPD_DDRGL_CPU0_SDA ; B = I3C_SPD_DDRGL_CPU0_LVC1_SDA

(kicad_pcb
	(version 20260206)
	(generator "pcbnew")
	(generator_version "10.0")
	(general
		(thickness 1.6)
		(legacy_teardrops no)
	)
	(paper "A4")
	(title_block
		(title "04192023_DAF0TMB3IC0_F0TG_MB_C_brd_V02_OCP.brd")
		(comment 1 "Grand Teton / footprints 1121-1123 of 8354")
	)
	(layers
		(0 "F.Cu" signal "TOP")
		(4 "In1.Cu" signal "GND")
		(6 "In2.Cu" signal "IN1")
		(8 "In3.Cu" signal "GND1")
		(10 "In4.Cu" signal "IN2")
		(12 "In5.Cu" signal "GND2")
		(14 "In6.Cu" signal "IN3")
		(16 "In7.Cu" signal "GND3")
		(18 "In8.Cu" signal "VCC")
		(20 "In9.Cu" signal "VCC1")
		(22 "In10.Cu" signal "GND4")
		(24 "In11.Cu" signal "IN4")
		(26 "In12.Cu" signal "GND5")
		(28 "In13.Cu" signal "IN5")
		(30 "In14.Cu" signal "GND6")
		(32 "In15.Cu" signal "IN6")
		(34 "In16.Cu" signal "GND7")
		(2 "B.Cu" signal "BOTTOM")
		(9 "F.Adhes" user "F.Adhesive")
		(11 "B.Adhes" user "B.Adhesive")
		(13 "F.Paste" user "Package Geometry/Pastemask Top")
		(15 "B.Paste" user "Package Geometry/Pastemask Bottom")
		(5 "F.SilkS" user "Ref Des/Silkscreen Top")
		(7 "B.SilkS" user "Ref Des/Silkscreen Bottom")
		(1 "F.Mask" user "Board Geometry/Soldermask Top")
		(3 "B.Mask" user "Board Geometry/Soldermask Bottom")
		(17 "Dwgs.User" user "User.Drawings")
		(19 "Cmts.User" user "User.Comments")
		(21 "Eco1.User" user "User.Eco1")
		(23 "Eco2.User" user "User.Eco2")
		(25 "Edge.Cuts" user "Board Geometry/Outline")
		(27 "Margin" user)
		(31 "F.CrtYd" user "Package Geometry/Place Bound Top")
		(29 "B.CrtYd" user "Package Geometry/Place Bound Bottom")
		(35 "F.Fab" user "Ref Des/Assembly Top")
		(33 "B.Fab" user "Ref Des/Assembly Bottom")
	)
	(footprint ""
		(layer "F.Cu")
		(at 435.102 -170.688 -90)
		(property "Reference" "R1300"
			(at 0 0 270)
			(layer "F.SilkS")
			(hide yes)
			(effects
				(font
					(size 1.27 1.27)
				)
			)
		)
		(property "Value" ""
			(at 0 0 270)
			(layer "F.Fab")
			(effects
				(font
					(size 1.27 1.27)
				)
			)
		)
		(duplicate_pad_numbers_are_jumpers no)
		(fp_line
			(start -0.7874 0.4064)
			(end -0.7874 -0.4064)
			(stroke
				(width 0.1524)
				(type default)
			)
			(layer "F.SilkS")
		)
		(fp_line
			(start 0.7874 0.4064)
			(end -0.7874 0.4064)
			(stroke
				(width 0.1524)
				(type default)
			)
			(layer "F.SilkS")
		)
		(fp_line
			(start -0.7874 -0.4064)
			(end 0.7874 -0.4064)
			(stroke
				(width 0.1524)
				(type default)
			)
			(layer "F.SilkS")
		)
		(fp_line
			(start 0.7874 -0.4064)
			(end 0.7874 0.4064)
			(stroke
				(width 0.1524)
				(type default)
			)
			(layer "F.SilkS")
		)
		(fp_line
			(start -0.67945 0.3048)
			(end -0.67945 -0.305054)
			(stroke
				(width 0.1)
				(type default)
			)
			(layer "F.Fab")
		)
		(fp_line
			(start -0.12065 0.3048)
			(end -0.67945 0.3048)
			(stroke
				(width 0.1)
				(type default)
			)
			(layer "F.Fab")
		)
		(fp_line
			(start 0.120396 0.3048)
			(end 0.120396 0.2794)
			(stroke
				(width 0.1)
				(type default)
			)
			(layer "F.Fab")
		)
		(fp_line
			(start 0.67945 0.3048)
			(end 0.120396 0.3048)
			(stroke
				(width 0.1)
				(type default)
			)
			(layer "F.Fab")
		)
		(fp_line
			(start -0.12065 0.2794)
			(end -0.12065 0.3048)
			(stroke
				(width 0.1)
				(type default)
			)
			(layer "F.Fab")
		)
		(fp_line
			(start 0.120396 0.2794)
			(end -0.12065 0.2794)
			(stroke
				(width 0.1)
				(type default)
			)
			(layer "F.Fab")
		)
		(fp_line
			(start -0.12065 -0.2794)
			(end 0.12065 -0.2794)
			(stroke
				(width 0.1)
				(type default)
			)
			(layer "F.Fab")
		)
		(fp_line
			(start 0.12065 -0.2794)
			(end 0.12065 -0.3048)
			(stroke
				(width 0.1)
				(type default)
			)
			(layer "F.Fab")
		)
		(fp_line
			(start 0.12065 -0.3048)
			(end 0.67945 -0.3048)
			(stroke
				(width 0.1)
				(type default)
			)
			(layer "F.Fab")
		)
		(fp_line
			(start 0.67945 -0.3048)
			(end 0.67945 0.3048)
			(stroke
				(width 0.1)
				(type default)
			)
			(layer "F.Fab")
		)
		(fp_line
			(start -0.67945 -0.305054)
			(end -0.12065 -0.305054)
			(stroke
				(width 0.1)
				(type default)
			)
			(layer "F.Fab")
		)
		(fp_line
			(start -0.12065 -0.305054)
			(end -0.12065 -0.2794)
			(stroke
				(width 0.1)
				(type default)
			)
			(layer "F.Fab")
		)
		(pad "1" smd rect
			(at -0.40005 0 90)
			(size 0.4572 0.508)
			(layers "F.Cu" "F.Mask" "F.Paste")
			(net "I3C_SPD_DDRGL_CPU0_SDA")
		)
		(pad "2" smd rect
			(at 0.40005 0 90)
			(size 0.4572 0.508)
			(layers "F.Cu" "F.Mask" "F.Paste")
			(net "I3C_SPD_DDRGL_CPU0_LVC1_SDA")
		)
	)
	(footprint ""
		(layer "F.Cu")
		(at 192.151 -137.632948 -90)
		(property "Reference" "R1567"
			(at 0 0 270)
			(layer "F.SilkS")
			(hide yes)
			(effects
				(font
					(size 1.27 1.27)
				)
			)
		)
		(property "Value" ""
			(at 0 0 270)
			(layer "F.Fab")
			(effects
				(font
					(size 1.27 1.27)
				)
			)
		)
		(duplicate_pad_numbers_are_jumpers no)
		(fp_line
			(start -0.7874 0.4064)
			(end -0.7874 -0.4064)
			(stroke
				(width 0.1524)
				(type default)
			)
			(layer "F.SilkS")
		)
		(fp_line
			(start 0.7874 0.4064)
			(end -0.7874 0.4064)
			(stroke
				(width 0.1524)
				(type default)
			)
			(layer "F.SilkS")
		)
		(fp_line
			(start -0.7874 -0.4064)
			(end 0.7874 -0.4064)
			(stroke
				(width 0.1524)
				(type default)
			)
			(layer "F.SilkS")
		)
		(fp_line
			(start 0.7874 -0.4064)
			(end 0.7874 0.4064)
			(stroke
				(width 0.1524)
				(type default)
			)
			(layer "F.SilkS")
		)
		(fp_line
			(start -0.67945 0.3048)
			(end -0.67945 -0.305054)
			(stroke
				(width 0.1)
				(type default)
			)
			(layer "F.Fab")
		)
		(fp_line
			(start -0.12065 0.3048)
			(end -0.67945 0.3048)
			(stroke
				(width 0.1)
				(type default)
			)
			(layer "F.Fab")
		)
		(fp_line
			(start 0.120396 0.3048)
			(end 0.120396 0.2794)
			(stroke
				(width 0.1)
				(type default)
			)
			(layer "F.Fab")
		)
		(fp_line
			(start 0.67945 0.3048)
			(end 0.120396 0.3048)
			(stroke
				(width 0.1)
				(type default)
			)
			(layer "F.Fab")
		)
		(fp_line
			(start -0.12065 0.2794)
			(end -0.12065 0.3048)
			(stroke
				(width 0.1)
				(type default)
			)
			(layer "F.Fab")
		)
		(fp_line
			(start 0.120396 0.2794)
			(end -0.12065 0.2794)
			(stroke
				(width 0.1)
				(type default)
			)
			(layer "F.Fab")
		)
		(fp_line
			(start -0.12065 -0.2794)
			(end 0.12065 -0.2794)
			(stroke
				(width 0.1)
				(type default)
			)
			(layer "F.Fab")
		)
		(fp_line
			(start 0.12065 -0.2794)
			(end 0.12065 -0.3048)
			(stroke
				(width 0.1)
				(type default)
			)
			(layer "F.Fab")
		)
		(fp_line
			(start 0.12065 -0.3048)
			(end 0.67945 -0.3048)
			(stroke
				(width 0.1)
				(type default)
			)
			(layer "F.Fab")
		)
		(fp_line
			(start 0.67945 -0.3048)
			(end 0.67945 0.3048)
			(stroke
				(width 0.1)
				(type default)
			)
			(layer "F.Fab")
		)
		(fp_line
			(start -0.67945 -0.305054)
			(end -0.12065 -0.305054)
			(stroke
				(width 0.1)
				(type default)
			)
			(layer "F.Fab")
		)
		(fp_line
			(start -0.12065 -0.305054)
			(end -0.12065 -0.2794)
			(stroke
				(width 0.1)
				(type default)
			)
			(layer "F.Fab")
		)
		(pad "1" smd circle
			(at -0.40005 0 270)
			(size 0 0)
			(layers "F.Cu" "F.Mask" "F.Paste")
			(net "PVDD18_S5_P0")
		)
		(pad "2" smd circle
			(at 0.40005 0 270)
			(size 0 0)
			(layers "F.Cu" "F.Mask" "F.Paste")
			(net "ROM_LS_EN")
		)
	)
	(footprint ""
		(layer "F.Cu")
		(at 332.071472 -395.066774 -90)
		(property "Reference" "R629"
			(at 0 0 270)
			(layer "F.SilkS")
			(hide yes)
			(effects
				(font
					(size 1.27 1.27)
				)
			)
		)
		(property "Value" ""
			(at 0 0 270)
			(layer "F.Fab")
			(effects
				(font
					(size 1.27 1.27)
				)
			)
		)
		(duplicate_pad_numbers_are_jumpers no)
		(fp_line
			(start -0.32512 0.175006)
			(end -0.32512 -0.175006)
			(stroke
				(width 0.1)
				(type default)
			)
			(layer "F.Fab")
		)
		(fp_line
			(start 0.32512 0.175006)
			(end -0.32512 0.175006)
			(stroke
				(width 0.1)
				(type default)
			)
			(layer "F.Fab")
		)
		(fp_line
			(start -0.32512 -0.175006)
			(end 0.32512 -0.175006)
			(stroke
				(width 0.1)
				(type default)
			)
			(layer "F.Fab")
		)
		(fp_line
			(start 0.32512 -0.175006)
			(end 0.32512 0.175006)
			(stroke
				(width 0.1)
				(type default)
			)
			(layer "F.Fab")
		)
		(pad "1" smd rect
			(at -0.2667 0 270)
			(size 0.3048 0.381)
			(layers "F.Cu" "F.Mask" "F.Paste")
			(net "CLK_100M_RETIMER_CPU0_P1_DN")
		)
		(pad "2" smd rect
			(at 0.2667 0 90)
			(size 0.3048 0.381)
			(layers "F.Cu" "F.Mask" "F.Paste")
			(net "GND")
		)
	)
)
